(kicad_pcb
	(version 20260206)
	(generator "pcbnew")
	(generator_version "10.0")
	(general
		(thickness 1.6)
		(legacy_teardrops no)
	)
	(paper "A4")
	(title_block
		(title "01162023_DA0F0TEBIF0_F0T_Expander_BD_F_brd_V02_OCP.brd")
		(comment 1 "Grand Teton / footprints 8292-8299 of 9728")
	)
	(layers
		(0 "F.Cu" signal "TOP")
		(4 "In1.Cu" signal "GND")
		(6 "In2.Cu" signal "VCC")
		(8 "In3.Cu" signal "VCC1")
		(10 "In4.Cu" signal "GND1")
		(12 "In5.Cu" signal "IN1")
		(14 "In6.Cu" signal "GND2")
		(16 "In7.Cu" signal "IN2")
		(18 "In8.Cu" signal "GND3")
		(20 "In9.Cu" signal "IN3")
		(22 "In10.Cu" signal "GND4")
		(24 "In11.Cu" signal "IN4")
		(26 "In12.Cu" signal "GND5")
		(28 "In13.Cu" signal "IN5")
		(30 "In14.Cu" signal "GND6")
		(32 "In15.Cu" signal "IN6")
		(34 "In16.Cu" signal "GND7")
		(2 "B.Cu" signal "BOTTOM")
		(9 "F.Adhes" user "F.Adhesive")
		(11 "B.Adhes" user "B.Adhesive")
		(13 "F.Paste" user "Package Geometry/Pastemask Top")
		(15 "B.Paste" user "Package Geometry/Pastemask Bottom")
		(5 "F.SilkS" user "Ref Des/Silkscreen Top")
		(7 "B.SilkS" user "Ref Des/Silkscreen Bottom")
		(1 "F.Mask" user "Board Geometry/Soldermask Top")
		(3 "B.Mask" user "Board Geometry/Soldermask Bottom")
		(17 "Dwgs.User" user "User.Drawings")
		(19 "Cmts.User" user "User.Comments")
		(21 "Eco1.User" user "User.Eco1")
		(23 "Eco2.User" user "User.Eco2")
		(25 "Edge.Cuts" user "Board Geometry/Outline")
		(27 "Margin" user)
		(31 "F.CrtYd" user "Package Geometry/Place Bound Top")
		(29 "B.CrtYd" user "Package Geometry/Place Bound Bottom")
		(35 "F.Fab" user "Ref Des/Assembly Top")
		(33 "B.Fab" user "Ref Des/Assembly Bottom")
	)
	(footprint ""
		(layer "B.Cu")
		(at 359.812082 -308.613556 90)
		(property "Reference" "C4374"
			(at 0 0 90)
			(layer "B.SilkS")
			(hide yes)
			(effects
				(font
					(size 1.27 1.27)
				)
				(justify mirror)
			)
		)
		(property "Value" ""
			(at 0 0 90)
			(layer "B.Fab")
			(effects
				(font
					(size 1.27 1.27)
				)
				(justify mirror)
			)
		)
		(duplicate_pad_numbers_are_jumpers no)
		(fp_line
			(start 1.2954 -0.5842)
			(end -1.2954 -0.5842)
			(stroke
				(width 0.1524)
				(type default)
			)
			(layer "B.SilkS")
		)
		(fp_line
			(start -1.2954 -0.5842)
			(end -1.2954 0.5842)
			(stroke
				(width 0.1524)
				(type default)
			)
			(layer "B.SilkS")
		)
		(fp_line
			(start 1.2954 0.5842)
			(end 1.2954 -0.5842)
			(stroke
				(width 0.1524)
				(type default)
			)
			(layer "B.SilkS")
		)
		(fp_line
			(start -1.2954 0.5842)
			(end 1.2954 0.5842)
			(stroke
				(width 0.1524)
				(type default)
			)
			(layer "B.SilkS")
		)
		(fp_line
			(start 0.8636 -0.4572)
			(end -0.8636 -0.4572)
			(stroke
				(width 0.1)
				(type default)
			)
			(layer "B.Fab")
		)
		(fp_line
			(start -0.8636 -0.4572)
			(end -0.8636 -0.4064)
			(stroke
				(width 0.1)
				(type default)
			)
			(layer "B.Fab")
		)
		(fp_line
			(start 1.1938 -0.4064)
			(end 0.8636 -0.4064)
			(stroke
				(width 0.1)
				(type default)
			)
			(layer "B.Fab")
		)
		(fp_line
			(start 0.8636 -0.4064)
			(end 0.8636 -0.4572)
			(stroke
				(width 0.1)
				(type default)
			)
			(layer "B.Fab")
		)
		(fp_line
			(start -0.8636 -0.4064)
			(end -1.1938 -0.4064)
			(stroke
				(width 0.1)
				(type default)
			)
			(layer "B.Fab")
		)
		(fp_line
			(start -1.1938 -0.4064)
			(end -1.1938 0.4064)
			(stroke
				(width 0.1)
				(type default)
			)
			(layer "B.Fab")
		)
		(fp_line
			(start 1.1938 0.4064)
			(end 1.1938 -0.4064)
			(stroke
				(width 0.1)
				(type default)
			)
			(layer "B.Fab")
		)
		(fp_line
			(start 0.8636 0.4064)
			(end 1.1938 0.4064)
			(stroke
				(width 0.1)
				(type default)
			)
			(layer "B.Fab")
		)
		(fp_line
			(start -0.8636 0.4064)
			(end -0.8636 0.4572)
			(stroke
				(width 0.1)
				(type default)
			)
			(layer "B.Fab")
		)
		(fp_line
			(start -1.1938 0.4064)
			(end -0.8636 0.4064)
			(stroke
				(width 0.1)
				(type default)
			)
			(layer "B.Fab")
		)
		(fp_line
			(start 0.8636 0.4572)
			(end 0.8636 0.4064)
			(stroke
				(width 0.1)
				(type default)
			)
			(layer "B.Fab")
		)
		(fp_line
			(start -0.8636 0.4572)
			(end 0.8636 0.4572)
			(stroke
				(width 0.1)
				(type default)
			)
			(layer "B.Fab")
		)
		(pad "1" smd rect
			(at 0.7366 0)
			(size 0.7112 0.8128)
			(layers "B.Cu" "B.Mask" "B.Paste")
			(net "P0V8_PEX3")
		)
		(pad "2" smd rect
			(at -0.7366 0)
			(size 0.7112 0.8128)
			(layers "B.Cu" "B.Mask" "B.Paste")
			(net "GND")
		)
	)
	(footprint ""
		(layer "B.Cu")
		(at 116.612416 -137.53846 90)
		(property "Reference" "PC32"
			(at 0 0 90)
			(layer "B.SilkS")
			(hide yes)
			(effects
				(font
					(size 1.27 1.27)
				)
				(justify mirror)
			)
		)
		(property "Value" ""
			(at 0 0 90)
			(layer "B.Fab")
			(effects
				(font
					(size 1.27 1.27)
				)
				(justify mirror)
			)
		)
		(duplicate_pad_numbers_are_jumpers no)
		(fp_line
			(start 1.524 -0.762)
			(end -1.524 -0.762)
			(stroke
				(width 0.1524)
				(type default)
			)
			(layer "B.SilkS")
		)
		(fp_line
			(start -1.524 -0.762)
			(end -1.524 0.762)
			(stroke
				(width 0.1524)
				(type default)
			)
			(layer "B.SilkS")
		)
		(fp_line
			(start 1.524 0.762)
			(end 1.524 -0.762)
			(stroke
				(width 0.1524)
				(type default)
			)
			(layer "B.SilkS")
		)
		(fp_line
			(start -1.524 0.762)
			(end 1.524 0.762)
			(stroke
				(width 0.1524)
				(type default)
			)
			(layer "B.SilkS")
		)
		(fp_line
			(start 1.1049 -0.724916)
			(end 1.1049 0.724916)
			(stroke
				(width 0.1)
				(type default)
			)
			(layer "B.Fab")
		)
		(fp_line
			(start -1.1049 -0.724916)
			(end 1.1049 -0.724916)
			(stroke
				(width 0.1)
				(type default)
			)
			(layer "B.Fab")
		)
		(fp_line
			(start 1.1049 0.724916)
			(end -1.1049 0.724916)
			(stroke
				(width 0.1)
				(type default)
			)
			(layer "B.Fab")
		)
		(fp_line
			(start -1.1049 0.724916)
			(end -1.1049 -0.724916)
			(stroke
				(width 0.1)
				(type default)
			)
			(layer "B.Fab")
		)
		(pad "1" smd rect
			(at 0.889 0 90)
			(size 1.016 1.27)
			(layers "B.Cu" "B.Mask" "B.Paste")
			(net "P3V3_AUX")
		)
		(pad "2" smd rect
			(at -0.889 0 90)
			(size 1.016 1.27)
			(layers "B.Cu" "B.Mask" "B.Paste")
			(net "GND")
		)
	)
	(footprint ""
		(layer "B.Cu")
		(at 403.245574 -296.37482)
		(property "Reference" "C1896"
			(at 0 0 0)
			(layer "B.SilkS")
			(hide yes)
			(effects
				(font
					(size 1.27 1.27)
				)
				(justify mirror)
			)
		)
		(property "Value" ""
			(at 0 0 0)
			(layer "B.Fab")
			(effects
				(font
					(size 1.27 1.27)
				)
				(justify mirror)
			)
		)
		(duplicate_pad_numbers_are_jumpers no)
		(fp_line
			(start -0.299974 -0.150114)
			(end -0.299974 0.150114)
			(stroke
				(width 0.1)
				(type default)
			)
			(layer "B.Fab")
		)
		(fp_line
			(start -0.299974 0.150114)
			(end 0.299974 0.150114)
			(stroke
				(width 0.1)
				(type default)
			)
			(layer "B.Fab")
		)
		(fp_line
			(start 0.299974 -0.150114)
			(end -0.299974 -0.150114)
			(stroke
				(width 0.1)
				(type default)
			)
			(layer "B.Fab")
		)
		(fp_line
			(start 0.299974 0.150114)
			(end 0.299974 -0.150114)
			(stroke
				(width 0.1)
				(type default)
			)
			(layer "B.Fab")
		)
		(pad "1" smd rect
			(at 0.2667 0 180)
			(size 0.3048 0.381)
			(layers "B.Cu" "B.Mask" "B.Paste")
			(net "P0V8_PEX3")
		)
		(pad "2" smd rect
			(at -0.2667 0 180)
			(size 0.3048 0.381)
			(layers "B.Cu" "B.Mask" "B.Paste")
			(net "GND")
		)
	)
	(footprint ""
		(layer "B.Cu")
		(at 343.154 -207.772 90)
		(property "Reference" "R4142"
			(at 0 0 90)
			(layer "B.SilkS")
			(hide yes)
			(effects
				(font
					(size 1.27 1.27)
				)
				(justify mirror)
			)
		)
		(property "Value" ""
			(at 0 0 90)
			(layer "B.Fab")
			(effects
				(font
					(size 1.27 1.27)
				)
				(justify mirror)
			)
		)
		(duplicate_pad_numbers_are_jumpers no)
		(fp_line
			(start 0.7874 -0.4064)
			(end -0.7874 -0.4064)
			(stroke
				(width 0.1524)
				(type default)
			)
			(layer "B.SilkS")
		)
		(fp_line
			(start -0.7874 -0.4064)
			(end -0.7874 0.4064)
			(stroke
				(width 0.1524)
				(type default)
			)
			(layer "B.SilkS")
		)
		(fp_line
			(start 0.7874 0.4064)
			(end 0.7874 -0.4064)
			(stroke
				(width 0.1524)
				(type default)
			)
			(layer "B.SilkS")
		)
		(fp_line
			(start -0.7874 0.4064)
			(end 0.7874 0.4064)
			(stroke
				(width 0.1524)
				(type default)
			)
			(layer "B.SilkS")
		)
		(fp_line
			(start 0.67945 -0.305054)
			(end 0.12065 -0.305054)
			(stroke
				(width 0.1)
				(type default)
			)
			(layer "B.Fab")
		)
		(fp_line
			(start 0.12065 -0.305054)
			(end 0.12065 -0.2794)
			(stroke
				(width 0.1)
				(type default)
			)
			(layer "B.Fab")
		)
		(fp_line
			(start -0.12065 -0.3048)
			(end -0.67945 -0.3048)
			(stroke
				(width 0.1)
				(type default)
			)
			(layer "B.Fab")
		)
		(fp_line
			(start -0.67945 -0.3048)
			(end -0.67945 0.3048)
			(stroke
				(width 0.1)
				(type default)
			)
			(layer "B.Fab")
		)
		(fp_line
			(start 0.12065 -0.2794)
			(end -0.12065 -0.2794)
			(stroke
				(width 0.1)
				(type default)
			)
			(layer "B.Fab")
		)
		(fp_line
			(start -0.12065 -0.2794)
			(end -0.12065 -0.3048)
			(stroke
				(width 0.1)
				(type default)
			)
			(layer "B.Fab")
		)
		(fp_line
			(start 0.12065 0.2794)
			(end 0.12065 0.3048)
			(stroke
				(width 0.1)
				(type default)
			)
			(layer "B.Fab")
		)
		(fp_line
			(start -0.120396 0.2794)
			(end 0.12065 0.2794)
			(stroke
				(width 0.1)
				(type default)
			)
			(layer "B.Fab")
		)
		(fp_line
			(start 0.67945 0.3048)
			(end 0.67945 -0.305054)
			(stroke
				(width 0.1)
				(type default)
			)
			(layer "B.Fab")
		)
		(fp_line
			(start 0.12065 0.3048)
			(end 0.67945 0.3048)
			(stroke
				(width 0.1)
				(type default)
			)
			(layer "B.Fab")
		)
		(fp_line
			(start -0.120396 0.3048)
			(end -0.120396 0.2794)
			(stroke
				(width 0.1)
				(type default)
			)
			(layer "B.Fab")
		)
		(fp_line
			(start -0.67945 0.3048)
			(end -0.120396 0.3048)
			(stroke
				(width 0.1)
				(type default)
			)
			(layer "B.Fab")
		)
		(pad "1" smd circle
			(at 0.40005 0 270)
			(size 0 0)
			(layers "B.Cu" "B.Mask" "B.Paste")
			(net "SSD14_CLK_EN_N")
		)
		(pad "2" smd circle
			(at -0.40005 0 270)
			(size 0 0)
			(layers "B.Cu" "B.Mask" "B.Paste")
			(net "SSD14_CLK_EN_R_N")
		)
	)
	(footprint ""
		(layer "B.Cu")
		(at 285.674816 -286.399732 90)
		(property "Reference" "C3334"
			(at 0 0 90)
			(layer "B.SilkS")
			(hide yes)
			(effects
				(font
					(size 1.27 1.27)
				)
				(justify mirror)
			)
		)
		(property "Value" ""
			(at 0 0 90)
			(layer "B.Fab")
			(effects
				(font
					(size 1.27 1.27)
				)
				(justify mirror)
			)
		)
		(duplicate_pad_numbers_are_jumpers no)
		(fp_line
			(start 0.299974 -0.150114)
			(end -0.299974 -0.150114)
			(stroke
				(width 0.1)
				(type default)
			)
			(layer "B.Fab")
		)
		(fp_line
			(start -0.299974 -0.150114)
			(end -0.299974 0.150114)
			(stroke
				(width 0.1)
				(type default)
			)
			(layer "B.Fab")
		)
		(fp_line
			(start 0.299974 0.150114)
			(end 0.299974 -0.150114)
			(stroke
				(width 0.1)
				(type default)
			)
			(layer "B.Fab")
		)
		(fp_line
			(start -0.299974 0.150114)
			(end 0.299974 0.150114)
			(stroke
				(width 0.1)
				(type default)
			)
			(layer "B.Fab")
		)
		(pad "1" smd rect
			(at 0.2667 0 270)
			(size 0.3048 0.381)
			(layers "B.Cu" "B.Mask" "B.Paste")
			(net "P1V25_SERDES_VDDPLL_PEX2")
		)
		(pad "2" smd rect
			(at -0.2667 0 270)
			(size 0.3048 0.381)
			(layers "B.Cu" "B.Mask" "B.Paste")
			(net "GND")
		)
	)
	(footprint ""
		(layer "B.Cu")
		(at 102.027736 -275.813774)
		(property "Reference" "PC6608"
			(at 0 0 0)
			(layer "B.SilkS")
			(hide yes)
			(effects
				(font
					(size 1.27 1.27)
				)
				(justify mirror)
			)
		)
		(property "Value" ""
			(at 0 0 0)
			(layer "B.Fab")
			(effects
				(font
					(size 1.27 1.27)
				)
				(justify mirror)
			)
		)
		(duplicate_pad_numbers_are_jumpers no)
		(fp_line
			(start -1.524 -0.762)
			(end -1.524 0.762)
			(stroke
				(width 0.1524)
				(type default)
			)
			(layer "B.SilkS")
		)
		(fp_line
			(start -1.524 0.762)
			(end 1.524 0.762)
			(stroke
				(width 0.1524)
				(type default)
			)
			(layer "B.SilkS")
		)
		(fp_line
			(start 1.524 -0.762)
			(end -1.524 -0.762)
			(stroke
				(width 0.1524)
				(type default)
			)
			(layer "B.SilkS")
		)
		(fp_line
			(start 1.524 0.762)
			(end 1.524 -0.762)
			(stroke
				(width 0.1524)
				(type default)
			)
			(layer "B.SilkS")
		)
		(fp_line
			(start -1.1049 -0.724916)
			(end 1.1049 -0.724916)
			(stroke
				(width 0.1)
				(type default)
			)
			(layer "B.Fab")
		)
		(fp_line
			(start -1.1049 0.724916)
			(end -1.1049 -0.724916)
			(stroke
				(width 0.1)
				(type default)
			)
			(layer "B.Fab")
		)
		(fp_line
			(start 1.1049 -0.724916)
			(end 1.1049 0.724916)
			(stroke
				(width 0.1)
				(type default)
			)
			(layer "B.Fab")
		)
		(fp_line
			(start 1.1049 0.724916)
			(end -1.1049 0.724916)
			(stroke
				(width 0.1)
				(type default)
			)
			(layer "B.Fab")
		)
		(pad "1" smd rect
			(at 0.889 0)
			(size 1.016 1.27)
			(layers "B.Cu" "B.Mask" "B.Paste")
			(net "SW_P12V_P0V8_PEX0_FLT")
		)
		(pad "2" smd rect
			(at -0.889 0)
			(size 1.016 1.27)
			(layers "B.Cu" "B.Mask" "B.Paste")
			(net "GND")
		)
	)
	(footprint ""
		(layer "B.Cu")
		(at 399.874994 -297.79976 90)
		(property "Reference" "C1904"
			(at 0 0 90)
			(layer "B.SilkS")
			(hide yes)
			(effects
				(font
					(size 1.27 1.27)
				)
				(justify mirror)
			)
		)
		(property "Value" ""
			(at 0 0 90)
			(layer "B.Fab")
			(effects
				(font
					(size 1.27 1.27)
				)
				(justify mirror)
			)
		)
		(duplicate_pad_numbers_are_jumpers no)
		(fp_line
			(start 0.299974 -0.150114)
			(end -0.299974 -0.150114)
			(stroke
				(width 0.1)
				(type default)
			)
			(layer "B.Fab")
		)
		(fp_line
			(start -0.299974 -0.150114)
			(end -0.299974 0.150114)
			(stroke
				(width 0.1)
				(type default)
			)
			(layer "B.Fab")
		)
		(fp_line
			(start 0.299974 0.150114)
			(end 0.299974 -0.150114)
			(stroke
				(width 0.1)
				(type default)
			)
			(layer "B.Fab")
		)
		(fp_line
			(start -0.299974 0.150114)
			(end 0.299974 0.150114)
			(stroke
				(width 0.1)
				(type default)
			)
			(layer "B.Fab")
		)
		(pad "1" smd rect
			(at 0.2667 0 270)
			(size 0.3048 0.381)
			(layers "B.Cu" "B.Mask" "B.Paste")
			(net "P0V8_PEX3")
		)
		(pad "2" smd rect
			(at -0.2667 0 270)
			(size 0.3048 0.381)
			(layers "B.Cu" "B.Mask" "B.Paste")
			(net "GND")
		)
	)
	(footprint ""
		(layer "B.Cu")
		(at 309.741824 -102.088696 180)
		(property "Reference" "R272"
			(at 0 0 0)
			(layer "B.SilkS")
			(hide yes)
			(effects
				(font
					(size 1.27 1.27)
				)
				(justify mirror)
			)
		)
		(property "Value" ""
			(at 0 0 0)
			(layer "B.Fab")
			(effects
				(font
					(size 1.27 1.27)
				)
				(justify mirror)
			)
		)
		(duplicate_pad_numbers_are_jumpers no)
		(fp_line
			(start 0.7874 0.4064)
			(end 0.7874 -0.4064)
			(stroke
				(width 0.1524)
				(type default)
			)
			(layer "B.SilkS")
		)
		(fp_line
			(start 0.7874 -0.4064)
			(end -0.7874 -0.4064)
			(stroke
				(width 0.1524)
				(type default)
			)
			(layer "B.SilkS")
		)
		(fp_line
			(start -0.7874 0.4064)
			(end 0.7874 0.4064)
			(stroke
				(width 0.1524)
				(type default)
			)
			(layer "B.SilkS")
		)
		(fp_line
			(start -0.7874 -0.4064)
			(end -0.7874 0.4064)
			(stroke
				(width 0.1524)
				(type default)
			)
			(layer "B.SilkS")
		)
		(fp_line
			(start 0.67945 0.3048)
			(end 0.67945 -0.305054)
			(stroke
				(width 0.1)
				(type default)
			)
			(layer "B.Fab")
		)
		(fp_line
			(start 0.67945 -0.305054)
			(end 0.12065 -0.305054)
			(stroke
				(width 0.1)
				(type default)
			)
			(layer "B.Fab")
		)
		(fp_line
			(start 0.12065 0.3048)
			(end 0.67945 0.3048)
			(stroke
				(width 0.1)
				(type default)
			)
			(layer "B.Fab")
		)
		(fp_line
			(start 0.12065 0.2794)
			(end 0.12065 0.3048)
			(stroke
				(width 0.1)
				(type default)
			)
			(layer "B.Fab")
		)
		(fp_line
			(start 0.12065 -0.2794)
			(end -0.12065 -0.2794)
			(stroke
				(width 0.1)
				(type default)
			)
			(layer "B.Fab")
		)
		(fp_line
			(start 0.12065 -0.305054)
			(end 0.12065 -0.2794)
			(stroke
				(width 0.1)
				(type default)
			)
			(layer "B.Fab")
		)
		(fp_line
			(start -0.120396 0.3048)
			(end -0.120396 0.2794)
			(stroke
				(width 0.1)
				(type default)
			)
			(layer "B.Fab")
		)
		(fp_line
			(start -0.120396 0.2794)
			(end 0.12065 0.2794)
			(stroke
				(width 0.1)
				(type default)
			)
			(layer "B.Fab")
		)
		(fp_line
			(start -0.12065 -0.2794)
			(end -0.12065 -0.3048)
			(stroke
				(width 0.1)
				(type default)
			)
			(layer "B.Fab")
		)
		(fp_line
			(start -0.12065 -0.3048)
			(end -0.67945 -0.3048)
			(stroke
				(width 0.1)
				(type default)
			)
			(layer "B.Fab")
		)
		(fp_line
			(start -0.67945 0.3048)
			(end -0.120396 0.3048)
			(stroke
				(width 0.1)
				(type default)
			)
			(layer "B.Fab")
		)
		(fp_line
			(start -0.67945 -0.3048)
			(end -0.67945 0.3048)
			(stroke
				(width 0.1)
				(type default)
			)
			(layer "B.Fab")
		)
		(pad "1" smd circle
			(at 0.40005 0)
			(size 0 0)
			(layers "B.Cu" "B.Mask" "B.Paste")
			(net "NCSI_NIC5_RXD1")
		)
		(pad "2" smd circle
			(at -0.40005 0)
			(size 0 0)
			(layers "B.Cu" "B.Mask" "B.Paste")
			(net "GND")
		)
	)
)
